# S9S_MB_2U (Grand Teton) — schematic netlist excerpt (pin names and nets, part order shuffled) for the footprints in the layout excerpt that follows; sources: Cadence DE-HDL packaged netlist, KiCad conversion of 03242023_DA0F0TMBIJ0_F0T_Motherboard_J_brd_V01_OCP.brd

R3974  Q_RES  0 5% EMPTY  pkg 0402LF  page 192 : A = P12V_E1S_SENSE_0 ; B = P12V_E1S_0_ISENSE_MAM_MAM

(kicad_pcb
	(version 20260206)
	(generator "pcbnew")
	(generator_version "10.0")
	(general
		(thickness 1.6)
		(legacy_teardrops no)
	)
	(paper "A4")
	(title_block
		(title "03242023_DA0F0TMBIJ0_F0T_Motherboard_J_brd_V01_OCP.brd")
		(comment 1 "Grand Teton / footprints 949-949 of 6105")
	)
	(layers
		(0 "F.Cu" signal "TOP")
		(4 "In1.Cu" signal "GND")
		(6 "In2.Cu" signal "IN1")
		(8 "In3.Cu" signal "GND1")
		(10 "In4.Cu" signal "IN2")
		(12 "In5.Cu" signal "GND2")
		(14 "In6.Cu" signal "IN3")
		(16 "In7.Cu" signal "GND3")
		(18 "In8.Cu" signal "VCC")
		(20 "In9.Cu" signal "VCC1")
		(22 "In10.Cu" signal "GND4")
		(24 "In11.Cu" signal "IN4")
		(26 "In12.Cu" signal "GND5")
		(28 "In13.Cu" signal "IN5")
		(30 "In14.Cu" signal "GND6")
		(32 "In15.Cu" signal "IN6")
		(34 "In16.Cu" signal "GND7")
		(2 "B.Cu" signal "BOTTOM")
		(9 "F.Adhes" user "F.Adhesive")
		(11 "B.Adhes" user "B.Adhesive")
		(13 "F.Paste" user "Package Geometry/Pastemask Top")
		(15 "B.Paste" user "Package Geometry/Pastemask Bottom")
		(5 "F.SilkS" user "Ref Des/Silkscreen Top")
		(7 "B.SilkS" user "Ref Des/Silkscreen Bottom")
		(1 "F.Mask" user "Board Geometry/Soldermask Top")
		(3 "B.Mask" user "Board Geometry/Soldermask Bottom")
		(17 "Dwgs.User" user "User.Drawings")
		(19 "Cmts.User" user "User.Comments")
		(21 "Eco1.User" user "User.Eco1")
		(23 "Eco2.User" user "User.Eco2")
		(25 "Edge.Cuts" user "Board Geometry/Outline")
		(27 "Margin" user)
		(31 "F.CrtYd" user "Package Geometry/Place Bound Top")
		(29 "B.CrtYd" user "Package Geometry/Place Bound Bottom")
		(35 "F.Fab" user "Ref Des/Assembly Top")
		(33 "B.Fab" user "Ref Des/Assembly Bottom")
	)
	(footprint ""
		(layer "F.Cu")
		(at 257.85953 -57.511442 180)
		(property "Reference" "R3974"
			(at 0 0 180)
			(layer "F.SilkS")
			(hide yes)
			(effects
				(font
					(size 1.27 1.27)
				)
			)
		)
		(property "Value" ""
			(at 0 0 180)
			(layer "F.Fab")
			(effects
				(font
					(size 1.27 1.27)
				)
			)
		)
		(duplicate_pad_numbers_are_jumpers no)
		(fp_line
			(start 0.7874 0.4064)
			(end -0.7874 0.4064)
			(stroke
				(width 0.1524)
				(type default)
			)
			(layer "F.SilkS")
		)
		(fp_line
			(start 0.7874 -0.4064)
			(end 0.7874 0.4064)
			(stroke
				(width 0.1524)
				(type default)
			)
			(layer "F.SilkS")
		)
		(fp_line
			(start -0.7874 0.4064)
			(end -0.7874 -0.4064)
			(stroke
				(width 0.1524)
				(type default)
			)
			(layer "F.SilkS")
		)
		(fp_line
			(start -0.7874 -0.4064)
			(end 0.7874 -0.4064)
			(stroke
				(width 0.1524)
				(type default)
			)
			(layer "F.SilkS")
		)
		(fp_line
			(start 0.67945 0.3048)
			(end 0.120396 0.3048)
			(stroke
				(width 0.1)
				(type default)
			)
			(layer "F.Fab")
		)
		(fp_line
			(start 0.67945 -0.3048)
			(end 0.67945 0.3048)
			(stroke
				(width 0.1)
				(type default)
			)
			(layer "F.Fab")
		)
		(fp_line
			(start 0.12065 -0.2794)
			(end 0.12065 -0.3048)
			(stroke
				(width 0.1)
				(type default)
			)
			(layer "F.Fab")
		)
		(fp_line
			(start 0.12065 -0.3048)
			(end 0.67945 -0.3048)
			(stroke
				(width 0.1)
				(type default)
			)
			(layer "F.Fab")
		)
		(fp_line
			(start 0.120396 0.3048)
			(end 0.120396 0.2794)
			(stroke
				(width 0.1)
				(type default)
			)
			(layer "F.Fab")
		)
		(fp_line
			(start 0.120396 0.2794)
			(end -0.12065 0.2794)
			(stroke
				(width 0.1)
				(type default)
			)
			(layer "F.Fab")
		)
		(fp_line
			(start -0.12065 0.3048)
			(end -0.67945 0.3048)
			(stroke
				(width 0.1)
				(type default)
			)
			(layer "F.Fab")
		)
		(fp_line
			(start -0.12065 0.2794)
			(end -0.12065 0.3048)
			(stroke
				(width 0.1)
				(type default)
			)
			(layer "F.Fab")
		)
		(fp_line
			(start -0.12065 -0.2794)
			(end 0.12065 -0.2794)
			(stroke
				(width 0.1)
				(type default)
			)
			(layer "F.Fab")
		)
		(fp_line
			(start -0.12065 -0.305054)
			(end -0.12065 -0.2794)
			(stroke
				(width 0.1)
				(type default)
			)
			(layer "F.Fab")
		)
		(fp_line
			(start -0.67945 0.3048)
			(end -0.67945 -0.305054)
			(stroke
				(width 0.1)
				(type default)
			)
			(layer "F.Fab")
		)
		(fp_line
			(start -0.67945 -0.305054)
			(end -0.12065 -0.305054)
			(stroke
				(width 0.1)
				(type default)
			)
			(layer "F.Fab")
		)
		(pad "1" smd rect
			(at -0.40005 0)
			(size 0.4572 0.508)
			(layers "F.Cu" "F.Mask" "F.Paste")
			(net "P12V_E1S_SENSE_0")
		)
		(pad "2" smd rect
			(at 0.40005 0)
			(size 0.4572 0.508)
			(layers "F.Cu" "F.Mask" "F.Paste")
			(net "P12V_E1S_0_ISENSE_MAM_MAM")
		)
	)
)
